FILE_TYPE=LIBRARY_PARTS;
primitive 'MC74VHC1G32DTT1G';
  pin
    'OUT_Y':
      PIN_NUMBER='(4)';
      OUTPUT_LOAD='(1.0,-1.0)';
    'IN_B':
      PIN_NUMBER='(1)';
      INPUT_LOAD='(-0.01,0.01)';
    'IN_A':
      PIN_NUMBER='(2)';
      INPUT_LOAD='(-0.01,0.01)';
    'GND':
      PIN_NUMBER='(3)';
      PINUSE='POWER';
      NO_LOAD_CHECK='Both';
      NO_IO_CHECK='Both';
      NO_ASSERT_CHECK='TRUE';
      NO_DIR_CHECK='TRUE';
      ALLOW_CONNECT='TRUE';
    'VCC':
      PIN_NUMBER='(5)';
      PINUSE='POWER';
      NO_LOAD_CHECK='Both';
      NO_IO_CHECK='Both';
      NO_ASSERT_CHECK='TRUE';
      NO_DIR_CHECK='TRUE';
      ALLOW_CONNECT='TRUE';
  end_pin;
  body
    PART_NAME='MC74VHC1G32DTT1G';
    BODY_NAME='MC74VHC1G32DTT1G';
    PHYS_DES_PREFIX='U';
    CLASS='IC';
  end_body;
end_primitive;

END.
